# T6G (Grand Teton) — schematic netlist excerpt (pin names and nets, part order shuffled) for the footprints in the layout excerpt that follows; sources: Cadence DE-HDL packaged netlist, KiCad conversion of 04192023_DAF0TMB3IC0_F0TG_MB_C_brd_V02_OCP.brd

R1523  Q_RES  0 5% CHIP  pkg 0402LF  page 142 : A = HP_LVC3_OCP_V3_2_P12V_PWRGD ; B = HP_LVC3_OCP_V3_2_P12V_PWRGD_R2
C219  Q_CAP  0.1UF 25V 10% X7R  pkg 0402  page 166 : A = P1V8_AUX ; B = GND

(kicad_pcb
	(version 20260206)
	(generator "pcbnew")
	(generator_version "10.0")
	(general
		(thickness 1.6)
		(legacy_teardrops no)
	)
	(paper "A4")
	(title_block
		(title "04192023_DAF0TMB3IC0_F0TG_MB_C_brd_V02_OCP.brd")
		(comment 1 "Grand Teton / footprints 1513-1514 of 8354")
	)
	(layers
		(0 "F.Cu" signal "TOP")
		(4 "In1.Cu" signal "GND")
		(6 "In2.Cu" signal "IN1")
		(8 "In3.Cu" signal "GND1")
		(10 "In4.Cu" signal "IN2")
		(12 "In5.Cu" signal "GND2")
		(14 "In6.Cu" signal "IN3")
		(16 "In7.Cu" signal "GND3")
		(18 "In8.Cu" signal "VCC")
		(20 "In9.Cu" signal "VCC1")
		(22 "In10.Cu" signal "GND4")
		(24 "In11.Cu" signal "IN4")
		(26 "In12.Cu" signal "GND5")
		(28 "In13.Cu" signal "IN5")
		(30 "In14.Cu" signal "GND6")
		(32 "In15.Cu" signal "IN6")
		(34 "In16.Cu" signal "GND7")
		(2 "B.Cu" signal "BOTTOM")
		(9 "F.Adhes" user "F.Adhesive")
		(11 "B.Adhes" user "B.Adhesive")
		(13 "F.Paste" user "Package Geometry/Pastemask Top")
		(15 "B.Paste" user "Package Geometry/Pastemask Bottom")
		(5 "F.SilkS" user "Ref Des/Silkscreen Top")
		(7 "B.SilkS" user "Ref Des/Silkscreen Bottom")
		(1 "F.Mask" user "Board Geometry/Soldermask Top")
		(3 "B.Mask" user "Board Geometry/Soldermask Bottom")
		(17 "Dwgs.User" user "User.Drawings")
		(19 "Cmts.User" user "User.Comments")
		(21 "Eco1.User" user "User.Eco1")
		(23 "Eco2.User" user "User.Eco2")
		(25 "Edge.Cuts" user "Board Geometry/Outline")
		(27 "Margin" user)
		(31 "F.CrtYd" user "Package Geometry/Place Bound Top")
		(29 "B.CrtYd" user "Package Geometry/Place Bound Bottom")
		(35 "F.Fab" user "Ref Des/Assembly Top")
		(33 "B.Fab" user "Ref Des/Assembly Bottom")
	)
	(footprint ""
		(layer "F.Cu")
		(at 57.40908 -52.53228)
		(property "Reference" "R1523"
			(at 0 0 0)
			(layer "F.SilkS")
			(hide yes)
			(effects
				(font
					(size 1.27 1.27)
				)
			)
		)
		(property "Value" ""
			(at 0 0 0)
			(layer "F.Fab")
			(effects
				(font
					(size 1.27 1.27)
				)
			)
		)
		(duplicate_pad_numbers_are_jumpers no)
		(fp_line
			(start -0.7874 -0.4064)
			(end 0.7874 -0.4064)
			(stroke
				(width 0.1524)
				(type default)
			)
			(layer "F.SilkS")
		)
		(fp_line
			(start -0.7874 0.4064)
			(end -0.7874 -0.4064)
			(stroke
				(width 0.1524)
				(type default)
			)
			(layer "F.SilkS")
		)
		(fp_line
			(start 0.7874 -0.4064)
			(end 0.7874 0.4064)
			(stroke
				(width 0.1524)
				(type default)
			)
			(layer "F.SilkS")
		)
		(fp_line
			(start 0.7874 0.4064)
			(end -0.7874 0.4064)
			(stroke
				(width 0.1524)
				(type default)
			)
			(layer "F.SilkS")
		)
		(fp_line
			(start -0.67945 -0.305054)
			(end -0.12065 -0.305054)
			(stroke
				(width 0.1)
				(type default)
			)
			(layer "F.Fab")
		)
		(fp_line
			(start -0.67945 0.3048)
			(end -0.67945 -0.305054)
			(stroke
				(width 0.1)
				(type default)
			)
			(layer "F.Fab")
		)
		(fp_line
			(start -0.12065 -0.305054)
			(end -0.12065 -0.2794)
			(stroke
				(width 0.1)
				(type default)
			)
			(layer "F.Fab")
		)
		(fp_line
			(start -0.12065 -0.2794)
			(end 0.12065 -0.2794)
			(stroke
				(width 0.1)
				(type default)
			)
			(layer "F.Fab")
		)
		(fp_line
			(start -0.12065 0.2794)
			(end -0.12065 0.3048)
			(stroke
				(width 0.1)
				(type default)
			)
			(layer "F.Fab")
		)
		(fp_line
			(start -0.12065 0.3048)
			(end -0.67945 0.3048)
			(stroke
				(width 0.1)
				(type default)
			)
			(layer "F.Fab")
		)
		(fp_line
			(start 0.120396 0.2794)
			(end -0.12065 0.2794)
			(stroke
				(width 0.1)
				(type default)
			)
			(layer "F.Fab")
		)
		(fp_line
			(start 0.120396 0.3048)
			(end 0.120396 0.2794)
			(stroke
				(width 0.1)
				(type default)
			)
			(layer "F.Fab")
		)
		(fp_line
			(start 0.12065 -0.3048)
			(end 0.67945 -0.3048)
			(stroke
				(width 0.1)
				(type default)
			)
			(layer "F.Fab")
		)
		(fp_line
			(start 0.12065 -0.2794)
			(end 0.12065 -0.3048)
			(stroke
				(width 0.1)
				(type default)
			)
			(layer "F.Fab")
		)
		(fp_line
			(start 0.67945 -0.3048)
			(end 0.67945 0.3048)
			(stroke
				(width 0.1)
				(type default)
			)
			(layer "F.Fab")
		)
		(fp_line
			(start 0.67945 0.3048)
			(end 0.120396 0.3048)
			(stroke
				(width 0.1)
				(type default)
			)
			(layer "F.Fab")
		)
		(pad "1" smd circle
			(at -0.40005 0)
			(size 0 0)
			(layers "F.Cu" "F.Mask" "F.Paste")
			(net "HP_LVC3_OCP_V3_2_P12V_PWRGD")
		)
		(pad "2" smd circle
			(at 0.40005 0)
			(size 0 0)
			(layers "F.Cu" "F.Mask" "F.Paste")
			(net "HP_LVC3_OCP_V3_2_P12V_PWRGD_R2")
		)
	)
	(footprint ""
		(layer "F.Cu")
		(at 347.899736 -25.529286)
		(property "Reference" "C219"
			(at 0 0 0)
			(layer "F.SilkS")
			(hide yes)
			(effects
				(font
					(size 1.27 1.27)
				)
			)
		)
		(property "Value" ""
			(at 0 0 0)
			(layer "F.Fab")
			(effects
				(font
					(size 1.27 1.27)
				)
			)
		)
		(duplicate_pad_numbers_are_jumpers no)
		(fp_line
			(start -0.7874 -0.4064)
			(end 0.7874 -0.4064)
			(stroke
				(width 0.1524)
				(type default)
			)
			(layer "F.SilkS")
		)
		(fp_line
			(start -0.7874 0.4064)
			(end -0.7874 -0.4064)
			(stroke
				(width 0.1524)
				(type default)
			)
			(layer "F.SilkS")
		)
		(fp_line
			(start 0.7874 -0.4064)
			(end 0.7874 0.4064)
			(stroke
				(width 0.1524)
				(type default)
			)
			(layer "F.SilkS")
		)
		(fp_line
			(start 0.7874 0.4064)
			(end -0.7874 0.4064)
			(stroke
				(width 0.1524)
				(type default)
			)
			(layer "F.SilkS")
		)
		(fp_line
			(start -0.67945 -0.305054)
			(end -0.12065 -0.305054)
			(stroke
				(width 0.1)
				(type default)
			)
			(layer "F.Fab")
		)
		(fp_line
			(start -0.67945 0.3048)
			(end -0.67945 -0.305054)
			(stroke
				(width 0.1)
				(type default)
			)
			(layer "F.Fab")
		)
		(fp_line
			(start -0.12065 -0.305054)
			(end -0.12065 -0.2794)
			(stroke
				(width 0.1)
				(type default)
			)
			(layer "F.Fab")
		)
		(fp_line
			(start -0.12065 -0.2794)
			(end 0.12065 -0.2794)
			(stroke
				(width 0.1)
				(type default)
			)
			(layer "F.Fab")
		)
		(fp_line
			(start -0.12065 0.2794)
			(end -0.12065 0.3048)
			(stroke
				(width 0.1)
				(type default)
			)
			(layer "F.Fab")
		)
		(fp_line
			(start -0.12065 0.3048)
			(end -0.67945 0.3048)
			(stroke
				(width 0.1)
				(type default)
			)
			(layer "F.Fab")
		)
		(fp_line
			(start 0.120396 0.2794)
			(end -0.12065 0.2794)
			(stroke
				(width 0.1)
				(type default)
			)
			(layer "F.Fab")
		)
		(fp_line
			(start 0.120396 0.3048)
			(end 0.120396 0.2794)
			(stroke
				(width 0.1)
				(type default)
			)
			(layer "F.Fab")
		)
		(fp_line
			(start 0.12065 -0.3048)
			(end 0.67945 -0.3048)
			(stroke
				(width 0.1)
				(type default)
			)
			(layer "F.Fab")
		)
		(fp_line
			(start 0.12065 -0.2794)
			(end 0.12065 -0.3048)
			(stroke
				(width 0.1)
				(type default)
			)
			(layer "F.Fab")
		)
		(fp_line
			(start 0.67945 -0.3048)
			(end 0.67945 0.3048)
			(stroke
				(width 0.1)
				(type default)
			)
			(layer "F.Fab")
		)
		(fp_line
			(start 0.67945 0.3048)
			(end 0.120396 0.3048)
			(stroke
				(width 0.1)
				(type default)
			)
			(layer "F.Fab")
		)
		(pad "1" smd circle
			(at -0.40005 0)
			(size 0 0)
			(layers "F.Cu" "F.Mask" "F.Paste")
			(net "P1V8_AUX")
		)
		(pad "2" smd circle
			(at 0.40005 0)
			(size 0 0)
			(layers "F.Cu" "F.Mask" "F.Paste")
			(net "GND")
		)
	)
)
